FILE_TYPE = CONNECTIVITY;
{Allegro Design Entry HDL 17.2-2016 S081 (4005846) 1/11/2022}
"PAGE_NUMBER" = 210;
0"NC";
1"P3V3_AUX\g";
2"P3V3_AUX\g";
3"P3V3_AUX\g";
4"GND\g";
5"GND\g";
6"GND\g";
7"GND\g";
8"P3V3_AUX_BMC_D";
9"JTAG_BMC_PLD_TDO";
10"JTAG_BMC_PLD_TDI";
11"TP_PLD_CONN_P5";
12"TP_PLD_CONN_P4";
13"JTAG_BMC_PLD_TMS";
14"JTAG_BMC_PLD_TCK";
15"JTAG_PLD_JTAGEN";
16"JTAG_PLD_TDO_R";
17"JTAG_PLD_TMS_R";
18"JTAG_PLD_TCK_R";
19"JTAG_BMC_PLD_TCK";
20"JTAG_BMC_PLD_TDO";
21"JTAG_BMC_PLD_TMS";
22"JTAG_BMC_PLD_TDI";
23"JTAG_PLD_TDI_R";
%"Q_RES"
"1","(-2125,3850)","0","pure_quanta","I19";
;
PART_NUMBER"CS03322FB03"
TOLERANCE"1%"
PACK_TYPE"0402LF"
VALUE"33.2"
MATERIAL"CHIP"
WATTAGE"1/16W"
$LOCATION"R803"
CDS_LIB"pure_quanta"
$LOCATION"R803"
CDS_LOCATION"R803"
$SEC"1"
CDS_SEC"1";
"B"
$PN"2"22;
"A"
$PN"1"23;
%"Q_RES"
"1","(-2125,3525)","0","pure_quanta","I20";
;
PART_NUMBER"CS03322FB03"
TOLERANCE"1%"
VALUE"33.2"
PACK_TYPE"0402LF"
WATTAGE"1/16W"
MATERIAL"CHIP"
$LOCATION"R804"
CDS_LIB"pure_quanta"
$LOCATION"R804"
CDS_LOCATION"R804"
$SEC"1"
CDS_SEC"1";
"B"
$PN"2"20;
"A"
$PN"1"16;
%"Q_RES"
"1","(-2125,3200)","0","pure_quanta","I25";
;
PART_NUMBER"CS03322FB03"
TOLERANCE"1%"
VALUE"33.2"
WATTAGE"1/16W"
PACK_TYPE"0402LF"
MATERIAL"CHIP"
$LOCATION"R805"
CDS_LIB"pure_quanta"
$LOCATION"R805"
CDS_LOCATION"R805"
$SEC"1"
CDS_SEC"1";
"B"
$PN"2"21;
"A"
$PN"1"17;
%"Q_RES"
"1","(-2125,2875)","0","pure_quanta","I54";
;
PART_NUMBER"CS03322FB03"
PACK_TYPE"0402LF"
TOLERANCE"1%"
VALUE"33.2"
MATERIAL"CHIP"
WATTAGE"1/16W"
$LOCATION"R806"
CDS_LIB"pure_quanta"
$LOCATION"R806"
CDS_LOCATION"R806"
$SEC"1"
CDS_SEC"1";
"B"
$PN"2"19;
"A"
$PN"1"18;
%"Q_RES"
"2","(-150,4125)","0","pure_quanta","I59";
;
PART_NUMBER"CS31002FB08"
MATERIAL"CHIP"
WATTAGE"1/16W"
TOLERANCE"1%"
PACK_TYPE"0402LF"
VALUE"10K"
$LOCATION"R929"
CDS_LIB"pure_quanta"
CDS_LOCATION"R929"
$SEC"1"
CDS_SEC"1";
"A"
$PN"1"1;
"B"
$PN"2"21;
%"Q_RES"
"2","(-450,4125)","0","pure_quanta","I60";
;
PART_NUMBER"CS31002FB08"
VALUE"10K"
MATERIAL"CHIP"
PACK_TYPE"0402LF"
WATTAGE"1/16W"
TOLERANCE"1%"
$LOCATION"R928"
CDS_LIB"pure_quanta"
CDS_LOCATION"R928"
$SEC"1"
CDS_SEC"1";
"A"
$PN"1"1;
"B"
$PN"2"20;
%"Q_RES"
"2","(-775,4125)","0","pure_quanta","I61";
;
PART_NUMBER"CS31002FB08"
WATTAGE"1/16W"
PACK_TYPE"0402LF"
VALUE"10K"
TOLERANCE"1%"
MATERIAL"CHIP"
$LOCATION"R927"
CDS_LIB"pure_quanta"
CDS_LOCATION"R927"
$SEC"1"
CDS_SEC"1";
"A"
$PN"1"1;
"B"
$PN"2"22;
%"UNIVERSAL_POWER"
"1","(-775,4525)","0","logical_power","I62";
;
HDL_POWER"P3V3_AUX"
CDS_LIB"logical_power";
"A"1;
%"Q_RES"
"2","(-150,2625)","0","pure_quanta","I63";
;
PART_NUMBER"CS24702FB06"
TOLERANCE"1%"
PACK_TYPE"0402LF"
MATERIAL"CHIP"
WATTAGE"1/16W"
VALUE"4.7K"
$LOCATION"R930"
CDS_LIB"pure_quanta"
CDS_LOCATION"R930"
$SEC"1"
CDS_SEC"1";
"A"
$PN"1"19;
"B"
$PN"2"4;
%"UNIVERSAL_GND"
"1","(-150,2400)","0","logical_power","I64";
;
CDS_LIB"logical_power"
HDL_POWER"GND";
"A"4;
%"Q_RES"
"2","(1650,1500)","0","pure_quanta","I75";
;
PART_NUMBER"CS31002FB08"
WATTAGE"1/16W"
VALUE"10K"
PACK_TYPE"0402LF"
MATERIAL"CHIP"
TOLERANCE"1%"
$LOCATION"R919"
CDS_LIB"pure_quanta"
CDS_LOCATION"R919"
$SEC"1"
CDS_SEC"1";
"A"
$PN"1"2;
"B"
$PN"2"15;
%"Q_RES"
"2","(1650,975)","0","pure_quanta","I76";
;
PART_NUMBER"CS21002FB06"
PACK_TYPE"0402LF"
MATERIAL"EMPTY"
TOLERANCE"1%"
VALUE"1K"
WATTAGE"1/16W"
$LOCATION"R920"
CDS_LIB"pure_quanta"
CDS_LOCATION"R920"
$SEC"1"
CDS_SEC"1";
"A"
$PN"1"15;
"B"
$PN"2"5;
%"UNIVERSAL_POWER"
"1","(1650,1825)","0","logical_power","I77";
;
HDL_POWER"P3V3_AUX"
CDS_LIB"logical_power";
"A"2;
%"UNIVERSAL_GND"
"1","(1650,625)","0","logical_power","I78";
;
CDS_LIB"logical_power"
HDL_POWER"GND"
ROOM"IO_SLOT";
"A"5;
%"CONN8_210HP1080BR1"
"1","(-425,750)","0","pure_quanta","I79";
;
PART_NUMBER"DFHD08MS392"
MATERIAL"IO"
PART_TYPE"THLF"
VALUE"CONN8_210-HP1-080BR1"
LOCATION"J43"
CDS_LIB"pure_quanta"
CDS_LMAN_SYM_OUTLINE"-50,225,50,-225"
NEEDS_NO_SIZE"True"
$SEC"1"
CDS_SEC"1";
"8"
$PN"8"14;
"7"
$PN"7"6;
"6"
$PN"6"13;
"5"
$PN"5"11;
"4"
$PN"4"12;
"3"
$PN"3"10;
"2"
$PN"2"9;
"1"
$PN"1"8;
%"Q_CAP"
"1","(-1200,1400)","2","pure_quanta","I86";
;
PART_NUMBER"CH4104K1B00"
VALUE"0.1UF"
VOLTAGE"25V"
MATERIAL"X7R"
TOLERANCE"10%"
PACK_TYPE"0402"
$LOCATION"C554"
CDS_LIB"pure_quanta"
$LOCATION"C554"
CDS_LOCATION"C554"
$SEC"1"
CDS_SEC"1";
"B"
$PN"2"7;
"A"
$PN"1"8;
%"Q_CAP"
"1","(-1075,1400)","0","pure_quanta","I88";
;
PART_NUMBER"CH6104KEA00"
VALUE"10UF"
PACK_TYPE"C0805"
VOLTAGE"25V"
TOLERANCE"10%"
MATERIAL"X6S"
$LOCATION"C563"
CDS_LIB"pure_quanta"
CDS_LOCATION"C563"
$SEC"1"
CDS_SEC"1";
"B"
$PN"2"7;
"A"
$PN"1"8;
%"UNIVERSAL_GND"
"1","(-1200,1075)","0","logical_power","I89";
;
CDS_LIB"logical_power"
HDL_POWER"GND";
"A"7;
%"UNIVERSAL_GND"
"1","(-750,225)","0","logical_power","I90";
;
CDS_LIB"logical_power"
HDL_POWER"GND";
"A"6;
%"SCHOTTKY_12"
"1","(-1925,1575)","0","pure_quanta","I91";
;
PART_NUMBER"BC005819Z40"
MATERIAL"IC"
VALUE"1N5819HW"
PART_TYPE"SMLF"
$LOCATION"D141"
CDS_LIB"pure_quanta"
NEEDS_NO_SIZE"TRUE"
CDS_LMAN_SYM_OUTLINE"-75,50,75,-50"
CDS_LOCATION"D141"
$SEC"1"
CDS_SEC"1";
"C"
$PN"2"8;
"A"
$PN"1"3;
%"UNIVERSAL_POWER"
"1","(-2250,1725)","0","logical_power","I92";
;
HDL_POWER"P3V3_AUX"
CDS_LIB"logical_power";
"A"3;
END.
